FILE_TYPE = CONNECTIVITY;
{Allegro Design Entry HDL 17.2-2016 S081 (4005846) 1/11/2022}
"PAGE_NUMBER" = 274;
0"NC";
1"PVCCIN_CPU1_PVCC\g";
2"PVCCIN_CPU1_PVCC\g";
3"SW_P12V_PVCCIN_CPU1_FLT\g";
4"PVCCIN_CPU1\g";
5"SW_P12V_PVCCIN_CPU1_FLT\g";
6"PVCCIN_CPU1\g";
7"GND\g";
8"GND\g";
9"GND\g";
10"GND\g";
11"GND\g";
12"GND\g";
13"GND\g";
14"GND\g";
15"GND\g";
16"GND\g";
17"GND\g";
18"GND\g";
19"GND\g";
20"GND\g";
21"GND\g";
22"GND\g";
23"IND_P1_CPL5";
24"SW_PVCCIN_CPU1_SW8";
25"SW_PVCCIN_CPU1_BOOTR7"CDS_PHYS_NET_NAME"SW_PVCCIN_CPU1_BOOTR7";
26"SW_PVCCIN_CPU1_SW7";
27"IND_P1_CPL7";
28"SW_PVCCIN_CPU1_BOOTR8"CDS_PHYS_NET_NAME"SW_PVCCIN_CPU1_BOOTR8";
29"IND_P1_CPL8";
30"SW_PVCCIN_CPU1_BOOT8_R";
31"SW_PVCCIN_CPU1_BOOT7_R";
32"SW_PVCCIN_CPU1_BOOT7"CDS_PHYS_NET_NAME"SW_PVCCIN_CPU1_BOOT7";
33"PVCCIN_CPU1_VDD7";
34"PVCCIN_CPU1_VREF"CDS_PHYS_NET_NAME"PVCCIN_CPU1_VREF";
35"PVCCIN_CPU1_IMON7";
36"PVCCIN_CPU1_VOS7";
37"PVCCIN_CPU1_LSET7";
38"SW_PVCCIN_CPU1_BOOT8"CDS_PHYS_NET_NAME"SW_PVCCIN_CPU1_BOOT8";
39"PVCCIN_CPU1_VOS8";
40"PVCCIN_CPU1_ATSEN";
41"PVCCIN_CPU1_PWM7";
42"PVCCIN_CPU1_VDD8";
43"PVCCIN_CPU1_VREF"CDS_PHYS_NET_NAME"PVCCIN_CPU1_VREF";
44"PVCCIN_CPU1_IMON8";
45"PVCCIN_CPU1_ATSEN";
46"PVCCIN_CPU1_PWM8";
47"PVCCIN_CPU1_LSET8";
%"UNIVERSAL_GND"
"1","(-7950,975)","0","logical_power","I1";
;
CDS_LIB"logical_power"
HDL_POWER"GND";
"A"7;
%"UNIVERSAL_GND"
"1","(-7550,1950)","0","logical_power","I10";
;
CDS_LIB"logical_power"
HDL_POWER"GND";
"A"9;
%"ISL99390FRZTR5935"
"1","(-6025,1700)","0","pure_quanta","I11";
;
PART_NUMBER"AL099390004"
PART_TYPE"SMLF"
MATERIAL"IC"
VALUE"ISL99390FRZ-TR5935"
LOCATION"PU23_P1_8"
NEEDS_NO_SIZE"TRUE"
CDS_LMAN_SYM_OUTLINE"-300,700,250,-650"
CDS_LIB"pure_quanta"
$SEC"1"
CDS_SEC"1";
"PGND2"
$PN"7_9-20_24"12;
"GL2"
$PN"41"0;
"GL1"
$PN"6"0;
"DNC"
$PN"31"0;
"EN"
$PN"35"42;
"PGND3"
$PN"40"12;
"VOS"
$PN"1"39;
"VIN2"
$PN"30"3;
"PGND1"
$PN"5"12;
"SW"
$PN"10_19"24;
"LSET"
$PN"37"47;
"IOUT"
$PN"38"44;
"TOUT_FLT"
$PN"36"45;
"PVCC"
$PN"4"1;
"PHASE"
$PN"32"28;
"VIN1"
$PN"25_29"3;
"BOOT"
$PN"33"38;
"AGND"
$PN"2"12;
"VCC"
$PN"3"42;
"REFIN"
$PN"39"43;
"PWM"
$PN"34"46;
%"Q_RES"
"2","(-7550,2700)","0","pure_quanta","I12";
;
PART_NUMBER"CS-2202FB01"
WATTAGE"1/16W"
MATERIAL"CHIP"
TOLERANCE"1%"
VALUE"2.2"
PACK_TYPE"0402LF"
LOCATION"PR287"
CDS_LIB"pure_quanta"
LOCATION"PR287"
$SEC"1"
CDS_SEC"1";
"A"
$PN"1"1;
"B"
$PN"2"42;
%"VCC15"
"1","(-7550,3025)","0","logical_power","I13";
;
HDL_POWER"PVCCIN_CPU1_PVCC"
CDS_LIB"logical_power";
"A"1;
%"UNIVERSAL_GND"
"1","(-7925,3800)","0","logical_power","I14";
;
CDS_LIB"logical_power"
HDL_POWER"GND";
"A"10;
%"Q_RES"
"2","(-7925,4025)","2","pure_quanta","I15";
;
PART_NUMBER"CS28872FB01"
WATTAGE"1/16W"
TOLERANCE"1%"
VALUE"8.87K"
PACK_TYPE"0402LF"
MATERIAL"EMPTY"
LOCATION"PR286"
CDS_LIB"pure_quanta"
LOCATION"PR286"
$SEC"1"
CDS_SEC"1";
"A"
$PN"1"37;
"B"
$PN"2"10;
%"Q_CAP"
"1","(-7125,2700)","0","pure_quanta","I18";
;
PART_NUMBER"CH5222KEB01"
MATERIAL"X6S"
TOLERANCE"10%"
VALUE"2.2UF"
VOLTAGE"10V"
PACK_TYPE"C0402"
LOCATION"PC481_P1_8"
CDS_LIB"pure_quanta"
LOCATION"PC481_P1_8"
$SEC"1"
CDS_SEC"1";
"B"
$PN"2"11;
"A"
$PN"1"1;
%"UNIVERSAL_GND"
"1","(-7125,2475)","0","logical_power","I19";
;
CDS_LIB"logical_power"
HDL_POWER"GND";
"A"11;
%"ISL99390FRZTR5935"
"1","(-6000,4525)","0","pure_quanta","I20";
;
PART_NUMBER"AL099390004"
PART_TYPE"SMLF"
MATERIAL"IC"
VALUE"ISL99390FRZ-TR5935"
LOCATION"PU24_P1_7"
NEEDS_NO_SIZE"TRUE"
CDS_LMAN_SYM_OUTLINE"-300,700,250,-650"
CDS_LIB"pure_quanta"
$SEC"1"
CDS_SEC"1";
"PGND2"
$PN"7_9-20_24"14;
"GL2"
$PN"41"0;
"GL1"
$PN"6"0;
"DNC"
$PN"31"0;
"EN"
$PN"35"33;
"PGND3"
$PN"40"14;
"VOS"
$PN"1"36;
"VIN2"
$PN"30"5;
"PGND1"
$PN"5"14;
"SW"
$PN"10_19"26;
"LSET"
$PN"37"37;
"IOUT"
$PN"38"35;
"TOUT_FLT"
$PN"36"40;
"PVCC"
$PN"4"2;
"PHASE"
$PN"32"25;
"VIN1"
$PN"25_29"5;
"BOOT"
$PN"33"32;
"AGND"
$PN"2"14;
"VCC"
$PN"3"33;
"REFIN"
$PN"39"34;
"PWM"
$PN"34"41;
%"UNIVERSAL_GND"
"1","(-5375,975)","0","logical_power","I21";
;
CDS_LIB"logical_power"
HDL_POWER"GND";
"A"12;
%"UNIVERSAL_GND"
"1","(-4775,1325)","0","logical_power","I22";
;
CDS_LIB"logical_power"
HDL_POWER"GND";
"A"13;
%"Q_INDUCTOR"
"1","(-4550,1475)","2","pure_quanta","I23";
;
PART_NUMBER"CV+12^0EZ03"
VALUE"120NH/69A"
PACK_TYPE"SMLF"
MATERIAL"IND"
LOCATION"PL106"
NEEDS_NO_SIZE"TRUE"
CDS_LIB"pure_quanta"
$SEC"1"
CDS_SEC"1";
"1"
$PN"1"29;
"2"
$PN"2"13;
%"Q_CAP"
"1","(-5225,2600)","0","pure_quanta","I24";
;
PART_NUMBER"TMP_QCH2336K1B12"
MATERIAL"X7R"
TOLERANCE"10%"
PACK_TYPE"0402"
VOLTAGE"50V"
VALUE"3300PF"
LOCATION"PC483_P1_8"
CDS_LIB"pure_quanta"
LOCATION"PC483_P1_8"
$SEC"1"
CDS_SEC"1";
"B"
$PN"2"18;
"A"
$PN"1"3;
%"UNIVERSAL_GND"
"1","(-5350,3800)","0","logical_power","I25";
;
CDS_LIB"logical_power"
HDL_POWER"GND";
"A"14;
%"Q_RES"
"1","(-4775,2150)","0","pure_quanta","I26";
;
PART_NUMBER"CS-3302FB01"
MATERIAL"CHIP"
TOLERANCE"1%"
VALUE"3.3"
PACK_TYPE"0402LF"
WATTAGE"1/16W"
LOCATION"PR1792"
CDS_LIB"pure_quanta"
$SEC"1"
CDS_SEC"1";
"B"
$PN"2"30;
"A"
$PN"1"38;
%"Q_CAP"
"1","(-4825,2600)","0","pure_quanta","I27";
;
PART_NUMBER"CH5103KEB01"
MATERIAL"X6S"
TOLERANCE"10%"
VOLTAGE"16V"
PACK_TYPE"C0402"
VALUE"1UF"
LOCATION"PC485_P1_8"
CDS_LIB"pure_quanta"
LOCATION"PC485_P1_8"
$SEC"1"
CDS_SEC"1";
"B"
$PN"2"18;
"A"
$PN"1"3;
%"Q_CAP"
"1","(-4425,2600)","0","pure_quanta","I28";
;
PART_NUMBER"CH6223MEA01"
MATERIAL"X6S"
TOLERANCE"20%"
VALUE"22UF"
VOLTAGE"16V"
PACK_TYPE"C0805"
LOCATION"PC489_P1_8"
CDS_LIB"pure_quanta"
LOCATION"PC489_P1_8"
$SEC"1"
CDS_SEC"1";
"B"
$PN"2"18;
"A"
$PN"1"3;
%"UNIVERSAL_GND"
"1","(-8025,4250)","0","logical_power","I29";
;
CDS_LIB"logical_power"
HDL_POWER"GND";
"A"15;
%"Q_RES"
"2","(-7950,1200)","2","pure_quanta","I3";
;
PART_NUMBER"CS28872FB01"
WATTAGE"1/16W"
MATERIAL"EMPTY"
TOLERANCE"1%"
VALUE"8.87K"
PACK_TYPE"0402LF"
LOCATION"PR285"
CDS_LIB"pure_quanta"
LOCATION"PR285"
$SEC"1"
CDS_SEC"1";
"A"
$PN"1"47;
"B"
$PN"2"7;
%"Q_CAP"
"2","(-7200,4325)","0","pure_quanta","I32";
;
PART_NUMBER"CH4104K1B00"
MATERIAL"X7R"
TOLERANCE"10%"
VALUE"0.1UF"
VOLTAGE"25V"
PACK_TYPE"0402"
LOCATION"PC1363"
CDS_LIB"pure_quanta"
$SEC"1"
CDS_SEC"1";
"A"
$PN"1"15;
"B"
$PN"2"34;
%"UNIVERSAL_GND"
"1","(-7525,4775)","0","logical_power","I33";
;
CDS_LIB"logical_power"
HDL_POWER"GND";
"A"16;
%"Q_CAP"
"1","(-7525,5025)","0","pure_quanta","I34";
;
PART_NUMBER"CH5222KEB01"
MATERIAL"X6S"
TOLERANCE"10%"
VALUE"2.2UF"
VOLTAGE"10V"
PACK_TYPE"C0402"
LOCATION"PC480"
CDS_LIB"pure_quanta"
LOCATION"PC480"
$SEC"1"
CDS_SEC"1";
"B"
$PN"2"16;
"A"
$PN"1"33;
%"VCC15"
"1","(-7525,5850)","0","logical_power","I35";
;
HDL_POWER"PVCCIN_CPU1_PVCC"
CDS_LIB"logical_power";
"A"2;
%"UNIVERSAL_GND"
"1","(-7100,5300)","0","logical_power","I36";
;
CDS_LIB"logical_power"
HDL_POWER"GND";
"A"17;
%"Q_CAP"
"1","(-5200,5425)","0","pure_quanta","I37";
;
PART_NUMBER"TMP_QCH2336K1B12"
MATERIAL"X7R"
TOLERANCE"10%"
VALUE"3300PF"
VOLTAGE"50V"
PACK_TYPE"0402"
LOCATION"PC484_P1_7"
CDS_LIB"pure_quanta"
LOCATION"PC484_P1_7"
$SEC"1"
CDS_SEC"1";
"B"
$PN"2"22;
"A"
$PN"1"5;
%"Q_RES"
"1","(-4750,4975)","0","pure_quanta","I39";
;
PART_NUMBER"CS-3302FB01"
WATTAGE"1/16W"
MATERIAL"CHIP"
TOLERANCE"1%"
VALUE"3.3"
PACK_TYPE"0402LF"
LOCATION"PR1793"
CDS_LIB"pure_quanta"
$SEC"1"
CDS_SEC"1";
"B"
$PN"2"31;
"A"
$PN"1"32;
%"UNIVERSAL_GND"
"1","(-8050,1425)","0","logical_power","I4";
;
CDS_LIB"logical_power"
HDL_POWER"GND";
"A"8;
%"Q_CAP"
"1","(-4800,5425)","0","pure_quanta","I40";
;
PART_NUMBER"CH5103KEB01"
MATERIAL"X6S"
TOLERANCE"10%"
VALUE"1UF"
VOLTAGE"16V"
PACK_TYPE"C0402"
LOCATION"PC486_P1_7"
CDS_LIB"pure_quanta"
LOCATION"PC486_P1_7"
$SEC"1"
CDS_SEC"1";
"B"
$PN"2"22;
"A"
$PN"1"5;
%"Q_CAP"
"1","(-4400,5425)","0","pure_quanta","I41";
;
PART_NUMBER"CH6223MEA01"
MATERIAL"X6S"
TOLERANCE"20%"
VALUE"22UF"
VOLTAGE"16V"
PACK_TYPE"C0805"
LOCATION"PC490_P1_7"
CDS_LIB"pure_quanta"
LOCATION"PC490_P1_7"
$SEC"1"
CDS_SEC"1";
"B"
$PN"2"22;
"A"
$PN"1"5;
%"Q_CAP"
"1","(-4050,1975)","2","pure_quanta","I42";
;
PART_NUMBER"CH4106K1B01"
MATERIAL"X7R"
TOLERANCE"10%"
VALUE"100NF"
VOLTAGE"50V"
PACK_TYPE"C0402"
LOCATION"PC487"
CDS_LIB"pure_quanta"
$SEC"1"
CDS_SEC"1";
"B"
$PN"2"28;
"A"
$PN"1"30;
%"Q_INDUCTOR4P_14"
"1","(-3500,1575)","0","pure_quanta","I43";
;
PART_NUMBER"CV+15^0TZ04"
VALUE"150NH"
MATERIAL"IND"
PART_TYPE"SMLF"
LOCATION"PL24"
NEEDS_NO_SIZE"TRUE"
CDS_LIB"pure_quanta"
SEC_TYPE""
SEC"1";
"1"
$PN"1"24;
"4"
$PN"4"4;
"3"
$PN"3"23;
"2"
$PN"2"29;
%"Q_RES"
"1","(-3525,1125)","0","pure_quanta","I44";
;
PART_NUMBER"CS00002JB13"
MATERIAL"CHIP"
TOLERANCE"5%"
VALUE"0"
WATTAGE"1/16W"
PACK_TYPE"0402LF"
LOCATION"PR289"
CDS_LIB"pure_quanta"
$SEC"1"
CDS_SEC"1";
"B"
$PN"2"4;
"A"
$PN"1"39;
%"Q_CAP"
"1","(-4025,2600)","0","pure_quanta","I46";
;
PART_NUMBER"CH6223MEA01"
TOLERANCE"20%"
VOLTAGE"16V"
PACK_TYPE"C0805"
VALUE"22UF"
MATERIAL"X6S"
LOCATION"PC491_P1_8"
CDS_LIB"pure_quanta"
LOCATION"PC491_P1_8"
$SEC"1"
CDS_SEC"1";
"B"
$PN"2"18;
"A"
$PN"1"3;
%"Q_CAP"
"1","(-3650,2600)","0","pure_quanta","I47";
;
PART_NUMBER"CH6223MEA01"
MATERIAL"X6S"
TOLERANCE"20%"
VALUE"22UF"
VOLTAGE"16V"
PACK_TYPE"C0805"
LOCATION"PC493_P1_8"
CDS_LIB"pure_quanta"
LOCATION"PC493_P1_8"
$SEC"1"
CDS_SEC"1";
"B"
$PN"2"18;
"A"
$PN"1"3;
%"UNIVERSAL_GND"
"1","(-3425,2175)","0","logical_power","I48";
;
CDS_LIB"logical_power"
HDL_POWER"GND";
"A"18;
%"VCC15"
"1","(-3425,2975)","0","logical_power","I49";
;
HDL_POWER"SW_P12V_PVCCIN_CPU1_FLT"
CDS_LIB"logical_power";
"A"3;
%"Q_RES"
"1","(-3525,3950)","0","pure_quanta","I50";
;
PART_NUMBER"CS00002JB13"
PACK_TYPE"0402LF"
VALUE"0"
MATERIAL"CHIP"
TOLERANCE"5%"
WATTAGE"1/16W"
LOCATION"PR290"
CDS_LIB"pure_quanta"
$SEC"1"
CDS_SEC"1";
"B"
$PN"2"6;
"A"
$PN"1"36;
%"UNIVERSAL_GND"
"1","(-2975,4150)","0","logical_power","I51";
;
CDS_LIB"logical_power"
HDL_POWER"GND";
"A"19;
%"Q_CAP"
"1","(-1925,1500)","0","pure_quanta","I52";
;
PART_NUMBER"CH5103KEB01"
TOLERANCE"10%"
VALUE"1UF"
VOLTAGE"16V"
MATERIAL"X6S"
PACK_TYPE"C0402"
LOCATION"PC495_P1_8"
CDS_LIB"pure_quanta"
LOCATION"PC495_P1_8"
$SEC"1"
CDS_SEC"1";
"B"
$PN"2"20;
"A"
$PN"1"4;
%"Q_CAP"
"1","(-1500,1500)","0","pure_quanta","I53";
;
PART_NUMBER"CH622KMEA03"
PACK_TYPE"C0805"
VOLTAGE"4V"
VALUE"22UF"
TOLERANCE"20%"
MATERIAL"X6S"
LOCATION"PC497_P1_8"
CDS_LIB"pure_quanta"
LOCATION"PC497_P1_8"
$SEC"1"
CDS_SEC"1";
"B"
$PN"2"20;
"A"
$PN"1"4;
%"Q_CAP"
"1","(-1075,1500)","0","pure_quanta","I54";
;
PART_NUMBER"CH622KMEA03"
PACK_TYPE"C0805"
VOLTAGE"4V"
VALUE"22UF"
TOLERANCE"20%"
MATERIAL"X6S"
LOCATION"PC499_P1_8"
CDS_LIB"pure_quanta"
LOCATION"PC499_P1_8"
$SEC"1"
CDS_SEC"1";
"B"
$PN"2"20;
"A"
$PN"1"4;
%"UNIVERSAL_GND"
"1","(-775,1125)","0","logical_power","I55";
;
CDS_LIB"logical_power"
HDL_POWER"GND";
"A"20;
%"VCC15"
"1","(-775,1900)","0","logical_power","I56";
;
HDL_POWER"PVCCIN_CPU1"
CDS_LIB"logical_power";
"A"4;
%"UNIVERSAL_GND"
"1","(-525,3950)","0","logical_power","I57";
;
CDS_LIB"logical_power"
HDL_POWER"GND";
"A"21;
%"Q_INDUCTOR4P_14"
"1","(-3550,4400)","0","pure_quanta","I58";
;
PART_NUMBER"CV+15^0TZ04"
MATERIAL"IND"
VALUE"150NH"
PART_TYPE"SMLF"
LOCATION"PL25"
NEEDS_NO_SIZE"TRUE"
CDS_LIB"pure_quanta"
SEC_TYPE""
SEC"1";
"1"
$PN"1"26;
"4"
$PN"4"6;
"3"
$PN"3"19;
"2"
$PN"2"27;
%"Q_CAP"
"1","(-4025,4800)","2","pure_quanta","I59";
;
PART_NUMBER"CH4106K1B01"
MATERIAL"X7R"
VALUE"100NF"
VOLTAGE"50V"
PACK_TYPE"C0402"
TOLERANCE"10%"
LOCATION"PC488"
CDS_LIB"pure_quanta"
$SEC"1"
CDS_SEC"1";
"B"
$PN"2"25;
"A"
$PN"1"31;
%"UNIVERSAL_GND"
"1","(-3400,5000)","0","logical_power","I60";
;
CDS_LIB"logical_power"
HDL_POWER"GND";
"A"22;
%"Q_CAP"
"1","(-4000,5425)","0","pure_quanta","I61";
;
PART_NUMBER"CH6223MEA01"
MATERIAL"X6S"
TOLERANCE"20%"
VALUE"22UF"
VOLTAGE"16V"
PACK_TYPE"C0805"
LOCATION"PC492_P1_7"
CDS_LIB"pure_quanta"
LOCATION"PC492_P1_7"
$SEC"1"
CDS_SEC"1";
"B"
$PN"2"22;
"A"
$PN"1"5;
%"Q_CAP"
"1","(-3625,5425)","0","pure_quanta","I62";
;
PART_NUMBER"CH6223MEA01"
PACK_TYPE"C0805"
MATERIAL"X6S"
TOLERANCE"20%"
VALUE"22UF"
VOLTAGE"16V"
LOCATION"PC494_P1_7"
CDS_LIB"pure_quanta"
LOCATION"PC494_P1_7"
$SEC"1"
CDS_SEC"1";
"B"
$PN"2"22;
"A"
$PN"1"5;
%"VCC15"
"1","(-3400,5800)","0","logical_power","I63";
;
HDL_POWER"SW_P12V_PVCCIN_CPU1_FLT"
CDS_LIB"logical_power";
"A"5;
%"Q_CAP"
"1","(-1675,4325)","0","pure_quanta","I64";
;
PART_NUMBER"CH5103KEB01"
MATERIAL"X6S"
TOLERANCE"10%"
VALUE"1UF"
VOLTAGE"16V"
PACK_TYPE"C0402"
LOCATION"PC496_P1_7"
CDS_LIB"pure_quanta"
LOCATION"PC496_P1_7"
$SEC"1"
CDS_SEC"1";
"B"
$PN"2"21;
"A"
$PN"1"6;
%"Q_CAP"
"1","(-1250,4325)","0","pure_quanta","I65";
;
PART_NUMBER"CH622KMEA03"
PACK_TYPE"C0805"
VOLTAGE"4V"
VALUE"22UF"
TOLERANCE"20%"
MATERIAL"X6S"
LOCATION"PC498_P1_7"
CDS_LIB"pure_quanta"
LOCATION"PC498_P1_7"
$SEC"1"
CDS_SEC"1";
"B"
$PN"2"21;
"A"
$PN"1"6;
%"Q_CAP"
"1","(-825,4325)","0","pure_quanta","I66";
;
PART_NUMBER"CH622KMEA03"
PACK_TYPE"C0805"
VOLTAGE"4V"
VALUE"22UF"
TOLERANCE"20%"
MATERIAL"X6S"
LOCATION"PC500_P1_7"
CDS_LIB"pure_quanta"
LOCATION"PC500_P1_7"
$SEC"1"
CDS_SEC"1";
"B"
$PN"2"21;
"A"
$PN"1"6;
%"VCC15"
"1","(-525,4725)","0","logical_power","I67";
;
HDL_POWER"PVCCIN_CPU1"
CDS_LIB"logical_power";
"A"6;
%"Q_RES"
"2","(-7525,5525)","0","pure_quanta","I68";
;
PART_NUMBER"CS-2202FB01"
WATTAGE"1/16W"
MATERIAL"CHIP"
TOLERANCE"1%"
VALUE"2.2"
PACK_TYPE"0402LF"
LOCATION"PR288"
CDS_LIB"pure_quanta"
LOCATION"PR288"
$SEC"1"
CDS_SEC"1";
"A"
$PN"1"2;
"B"
$PN"2"33;
%"Q_CAP"
"1","(-7100,5525)","0","pure_quanta","I69";
;
PART_NUMBER"CH5222KEB01"
MATERIAL"X6S"
TOLERANCE"10%"
VALUE"2.2UF"
VOLTAGE"10V"
PACK_TYPE"C0402"
LOCATION"PC482_P1_7"
CDS_LIB"pure_quanta"
LOCATION"PC482_P1_7"
$SEC"1"
CDS_SEC"1";
"B"
$PN"2"17;
"A"
$PN"1"2;
%"Q_CAP"
"2","(-7225,1500)","0","pure_quanta","I7";
;
PART_NUMBER"CH4104K1B00"
MATERIAL"X7R"
TOLERANCE"10%"
VALUE"0.1UF"
VOLTAGE"25V"
PACK_TYPE"0402"
LOCATION"PC1362"
CDS_LIB"pure_quanta"
$SEC"1"
CDS_SEC"1";
"A"
$PN"1"8;
"B"
$PN"2"43;
%"Q_CAP"
"1","(-7550,2200)","0","pure_quanta","I9";
;
PART_NUMBER"CH5222KEB01"
MATERIAL"X6S"
TOLERANCE"10%"
VALUE"2.2UF"
VOLTAGE"10V"
PACK_TYPE"C0402"
LOCATION"PC479"
CDS_LIB"pure_quanta"
LOCATION"PC479"
$SEC"1"
CDS_SEC"1";
"B"
$PN"2"9;
"A"
$PN"1"42;
END.
